# S9S_MB_2U (Grand Teton) — schematic netlist excerpt (pin names and nets, part order shuffled) for the footprints in the layout excerpt that follows; sources: Cadence DE-HDL packaged netlist, KiCad conversion of 03242023_DA0F0TMBIJ0_F0T_Motherboard_J_brd_V01_OCP.brd

C212  Q_CAP  47UF 4V 20% X6S  pkg C0805  page 74 : A = PVCCIN_CPU0 ; B = GND
C188  Q_CAP  0.1UF 25V 10% X7R  pkg 0402  page 155 : A = P3V3_AUX ; B = GND
R4649  Q_RES  1K 1% EMPTY  pkg 0402LF  page 167 : A = P3V3_AUX ; B = FM_P2E_BUF2_EQA0

(kicad_pcb
	(version 20260206)
	(generator "pcbnew")
	(generator_version "10.0")
	(general
		(thickness 1.6)
		(legacy_teardrops no)
	)
	(paper "A4")
	(title_block
		(title "03242023_DA0F0TMBIJ0_F0T_Motherboard_J_brd_V01_OCP.brd")
		(comment 1 "Grand Teton / footprints 1844-1846 of 6105")
	)
	(layers
		(0 "F.Cu" signal "TOP")
		(4 "In1.Cu" signal "GND")
		(6 "In2.Cu" signal "IN1")
		(8 "In3.Cu" signal "GND1")
		(10 "In4.Cu" signal "IN2")
		(12 "In5.Cu" signal "GND2")
		(14 "In6.Cu" signal "IN3")
		(16 "In7.Cu" signal "GND3")
		(18 "In8.Cu" signal "VCC")
		(20 "In9.Cu" signal "VCC1")
		(22 "In10.Cu" signal "GND4")
		(24 "In11.Cu" signal "IN4")
		(26 "In12.Cu" signal "GND5")
		(28 "In13.Cu" signal "IN5")
		(30 "In14.Cu" signal "GND6")
		(32 "In15.Cu" signal "IN6")
		(34 "In16.Cu" signal "GND7")
		(2 "B.Cu" signal "BOTTOM")
		(9 "F.Adhes" user "F.Adhesive")
		(11 "B.Adhes" user "B.Adhesive")
		(13 "F.Paste" user "Package Geometry/Pastemask Top")
		(15 "B.Paste" user "Package Geometry/Pastemask Bottom")
		(5 "F.SilkS" user "Ref Des/Silkscreen Top")
		(7 "B.SilkS" user "Ref Des/Silkscreen Bottom")
		(1 "F.Mask" user "Board Geometry/Soldermask Top")
		(3 "B.Mask" user "Board Geometry/Soldermask Bottom")
		(17 "Dwgs.User" user "User.Drawings")
		(19 "Cmts.User" user "User.Comments")
		(21 "Eco1.User" user "User.Eco1")
		(23 "Eco2.User" user "User.Eco2")
		(25 "Edge.Cuts" user "Board Geometry/Outline")
		(27 "Margin" user)
		(31 "F.CrtYd" user "Package Geometry/Place Bound Top")
		(29 "B.CrtYd" user "Package Geometry/Place Bound Bottom")
		(35 "F.Fab" user "Ref Des/Assembly Top")
		(33 "B.Fab" user "Ref Des/Assembly Bottom")
	)
	(footprint ""
		(layer "F.Cu")
		(at 39.26332 -400.153886 -90)
		(property "Reference" "R4649"
			(at 0 0 270)
			(layer "F.SilkS")
			(hide yes)
			(effects
				(font
					(size 1.27 1.27)
				)
			)
		)
		(property "Value" ""
			(at 0 0 270)
			(layer "F.Fab")
			(effects
				(font
					(size 1.27 1.27)
				)
			)
		)
		(duplicate_pad_numbers_are_jumpers no)
		(fp_line
			(start -0.7874 0.4064)
			(end -0.7874 -0.4064)
			(stroke
				(width 0.1524)
				(type default)
			)
			(layer "F.SilkS")
		)
		(fp_line
			(start 0.7874 0.4064)
			(end -0.7874 0.4064)
			(stroke
				(width 0.1524)
				(type default)
			)
			(layer "F.SilkS")
		)
		(fp_line
			(start -0.7874 -0.4064)
			(end 0.7874 -0.4064)
			(stroke
				(width 0.1524)
				(type default)
			)
			(layer "F.SilkS")
		)
		(fp_line
			(start 0.7874 -0.4064)
			(end 0.7874 0.4064)
			(stroke
				(width 0.1524)
				(type default)
			)
			(layer "F.SilkS")
		)
		(fp_line
			(start -0.67945 0.3048)
			(end -0.67945 -0.305054)
			(stroke
				(width 0.1)
				(type default)
			)
			(layer "F.Fab")
		)
		(fp_line
			(start -0.12065 0.3048)
			(end -0.67945 0.3048)
			(stroke
				(width 0.1)
				(type default)
			)
			(layer "F.Fab")
		)
		(fp_line
			(start 0.120396 0.3048)
			(end 0.120396 0.2794)
			(stroke
				(width 0.1)
				(type default)
			)
			(layer "F.Fab")
		)
		(fp_line
			(start 0.67945 0.3048)
			(end 0.120396 0.3048)
			(stroke
				(width 0.1)
				(type default)
			)
			(layer "F.Fab")
		)
		(fp_line
			(start -0.12065 0.2794)
			(end -0.12065 0.3048)
			(stroke
				(width 0.1)
				(type default)
			)
			(layer "F.Fab")
		)
		(fp_line
			(start 0.120396 0.2794)
			(end -0.12065 0.2794)
			(stroke
				(width 0.1)
				(type default)
			)
			(layer "F.Fab")
		)
		(fp_line
			(start -0.12065 -0.2794)
			(end 0.12065 -0.2794)
			(stroke
				(width 0.1)
				(type default)
			)
			(layer "F.Fab")
		)
		(fp_line
			(start 0.12065 -0.2794)
			(end 0.12065 -0.3048)
			(stroke
				(width 0.1)
				(type default)
			)
			(layer "F.Fab")
		)
		(fp_line
			(start 0.12065 -0.3048)
			(end 0.67945 -0.3048)
			(stroke
				(width 0.1)
				(type default)
			)
			(layer "F.Fab")
		)
		(fp_line
			(start 0.67945 -0.3048)
			(end 0.67945 0.3048)
			(stroke
				(width 0.1)
				(type default)
			)
			(layer "F.Fab")
		)
		(fp_line
			(start -0.67945 -0.305054)
			(end -0.12065 -0.305054)
			(stroke
				(width 0.1)
				(type default)
			)
			(layer "F.Fab")
		)
		(fp_line
			(start -0.12065 -0.305054)
			(end -0.12065 -0.2794)
			(stroke
				(width 0.1)
				(type default)
			)
			(layer "F.Fab")
		)
		(pad "1" smd circle
			(at -0.40005 0 270)
			(size 0 0)
			(layers "F.Cu" "F.Mask" "F.Paste")
			(net "P3V3_AUX")
		)
		(pad "2" smd circle
			(at 0.40005 0 270)
			(size 0 0)
			(layers "F.Cu" "F.Mask" "F.Paste")
			(net "FM_P2E_BUF2_EQA0")
		)
	)
	(footprint ""
		(layer "F.Cu")
		(at 387.633972 -29.10967 -90)
		(property "Reference" "C188"
			(at 0 0 270)
			(layer "F.SilkS")
			(hide yes)
			(effects
				(font
					(size 1.27 1.27)
				)
			)
		)
		(property "Value" ""
			(at 0 0 270)
			(layer "F.Fab")
			(effects
				(font
					(size 1.27 1.27)
				)
			)
		)
		(duplicate_pad_numbers_are_jumpers no)
		(fp_line
			(start -0.7874 0.4064)
			(end -0.7874 -0.4064)
			(stroke
				(width 0.1524)
				(type default)
			)
			(layer "F.SilkS")
		)
		(fp_line
			(start 0.7874 0.4064)
			(end -0.7874 0.4064)
			(stroke
				(width 0.1524)
				(type default)
			)
			(layer "F.SilkS")
		)
		(fp_line
			(start -0.7874 -0.4064)
			(end 0.7874 -0.4064)
			(stroke
				(width 0.1524)
				(type default)
			)
			(layer "F.SilkS")
		)
		(fp_line
			(start 0.7874 -0.4064)
			(end 0.7874 0.4064)
			(stroke
				(width 0.1524)
				(type default)
			)
			(layer "F.SilkS")
		)
		(fp_line
			(start -0.67945 0.3048)
			(end -0.67945 -0.305054)
			(stroke
				(width 0.1)
				(type default)
			)
			(layer "F.Fab")
		)
		(fp_line
			(start -0.12065 0.3048)
			(end -0.67945 0.3048)
			(stroke
				(width 0.1)
				(type default)
			)
			(layer "F.Fab")
		)
		(fp_line
			(start 0.120396 0.3048)
			(end 0.120396 0.2794)
			(stroke
				(width 0.1)
				(type default)
			)
			(layer "F.Fab")
		)
		(fp_line
			(start 0.67945 0.3048)
			(end 0.120396 0.3048)
			(stroke
				(width 0.1)
				(type default)
			)
			(layer "F.Fab")
		)
		(fp_line
			(start -0.12065 0.2794)
			(end -0.12065 0.3048)
			(stroke
				(width 0.1)
				(type default)
			)
			(layer "F.Fab")
		)
		(fp_line
			(start 0.120396 0.2794)
			(end -0.12065 0.2794)
			(stroke
				(width 0.1)
				(type default)
			)
			(layer "F.Fab")
		)
		(fp_line
			(start -0.12065 -0.2794)
			(end 0.12065 -0.2794)
			(stroke
				(width 0.1)
				(type default)
			)
			(layer "F.Fab")
		)
		(fp_line
			(start 0.12065 -0.2794)
			(end 0.12065 -0.3048)
			(stroke
				(width 0.1)
				(type default)
			)
			(layer "F.Fab")
		)
		(fp_line
			(start 0.12065 -0.3048)
			(end 0.67945 -0.3048)
			(stroke
				(width 0.1)
				(type default)
			)
			(layer "F.Fab")
		)
		(fp_line
			(start 0.67945 -0.3048)
			(end 0.67945 0.3048)
			(stroke
				(width 0.1)
				(type default)
			)
			(layer "F.Fab")
		)
		(fp_line
			(start -0.67945 -0.305054)
			(end -0.12065 -0.305054)
			(stroke
				(width 0.1)
				(type default)
			)
			(layer "F.Fab")
		)
		(fp_line
			(start -0.12065 -0.305054)
			(end -0.12065 -0.2794)
			(stroke
				(width 0.1)
				(type default)
			)
			(layer "F.Fab")
		)
		(pad "1" smd circle
			(at -0.40005 0 270)
			(size 0 0)
			(layers "F.Cu" "F.Mask" "F.Paste")
			(net "P3V3_AUX")
		)
		(pad "2" smd circle
			(at 0.40005 0 270)
			(size 0 0)
			(layers "F.Cu" "F.Mask" "F.Paste")
			(net "GND")
		)
	)
	(footprint ""
		(layer "F.Cu")
		(at 353.36988 -294.01008 180)
		(property "Reference" "C212"
			(at 0 0 180)
			(layer "F.SilkS")
			(hide yes)
			(effects
				(font
					(size 1.27 1.27)
				)
			)
		)
		(property "Value" ""
			(at 0 0 180)
			(layer "F.Fab")
			(effects
				(font
					(size 1.27 1.27)
				)
			)
		)
		(duplicate_pad_numbers_are_jumpers no)
		(fp_line
			(start 1.524 0.762)
			(end -1.524 0.762)
			(stroke
				(width 0.1524)
				(type default)
			)
			(layer "F.SilkS")
		)
		(fp_line
			(start 1.524 -0.762)
			(end 1.524 0.762)
			(stroke
				(width 0.1524)
				(type default)
			)
			(layer "F.SilkS")
		)
		(fp_line
			(start -1.524 0.762)
			(end -1.524 -0.762)
			(stroke
				(width 0.1524)
				(type default)
			)
			(layer "F.SilkS")
		)
		(fp_line
			(start -1.524 -0.762)
			(end 1.524 -0.762)
			(stroke
				(width 0.1524)
				(type default)
			)
			(layer "F.SilkS")
		)
		(fp_line
			(start 1.1049 0.724916)
			(end 1.1049 -0.724916)
			(stroke
				(width 0.1)
				(type default)
			)
			(layer "F.Fab")
		)
		(fp_line
			(start 1.1049 -0.724916)
			(end -1.1049 -0.724916)
			(stroke
				(width 0.1)
				(type default)
			)
			(layer "F.Fab")
		)
		(fp_line
			(start -1.1049 0.724916)
			(end 1.1049 0.724916)
			(stroke
				(width 0.1)
				(type default)
			)
			(layer "F.Fab")
		)
		(fp_line
			(start -1.1049 -0.724916)
			(end -1.1049 0.724916)
			(stroke
				(width 0.1)
				(type default)
			)
			(layer "F.Fab")
		)
		(pad "1" smd rect
			(at -0.889 0)
			(size 1.016 1.27)
			(layers "F.Cu" "F.Mask" "F.Paste")
			(net "PVCCIN_CPU0")
		)
		(pad "2" smd rect
			(at 0.889 0)
			(size 1.016 1.27)
			(layers "F.Cu" "F.Mask" "F.Paste")
			(net "GND")
		)
	)
)
